# TIMECARD (Time Appliance Project (Time Card)) — schematic netlist excerpt (pin names and nets, part order shuffled) for the footprints in the layout excerpt that follows; sources: Cadence DE-HDL packaged netlist, KiCad conversion of R4006-B0001-02_R01.brd

U40  NLASB3157DFT2G_SC88  pkg SOT363_V2  page 24
  B1  = NC
  GND  = SG
  B0  = FLASH_DQ3
  A  = FPGA_FLASH_DQ3
  VCC  = XP3R3V_FPGA
  \select\  = MUX2_SEL

C194  CAPACITOR  10UF 25V 20%  pkg SMC_0805R_H057  page 30 : \1\ = XP1R2V_FPGA ; \2\ = SG

(kicad_pcb
	(version 20260206)
	(generator "pcbnew")
	(generator_version "10.0")
	(general
		(thickness 1.6)
		(legacy_teardrops no)
	)
	(paper "A4")
	(title_block
		(title "timecard-production-celestica-r4006 — R4006-B0001-02_R01.brd")
		(comment 1 "Time Appliance Project (Time Card) / footprints 76-77 of 1113")
	)
	(layers
		(0 "F.Cu" signal "TOP")
		(4 "In1.Cu" signal "L02_GND1")
		(6 "In2.Cu" signal "L03_SIG1")
		(8 "In3.Cu" signal "L04_GND2")
		(10 "In4.Cu" signal "L05_VCC1")
		(12 "In5.Cu" signal "L06_VCC2")
		(14 "In6.Cu" signal "L07_GND3")
		(16 "In7.Cu" signal "L08_SIG2")
		(18 "In8.Cu" signal "L09_GND4")
		(2 "B.Cu" signal "BOTTOM")
		(9 "F.Adhes" user "F.Adhesive")
		(11 "B.Adhes" user "B.Adhesive")
		(13 "F.Paste" user "Package Geometry/Pastemask Top")
		(15 "B.Paste" user "Package Geometry/Pastemask Bottom")
		(5 "F.SilkS" user "Ref Des/Silkscreen Top")
		(7 "B.SilkS" user "Ref Des/Silkscreen Bottom")
		(1 "F.Mask" user "Board Geometry/Soldermask Top")
		(3 "B.Mask" user "Board Geometry/Soldermask Bottom")
		(17 "Dwgs.User" user "User.Drawings")
		(19 "Cmts.User" user "User.Comments")
		(21 "Eco1.User" user "User.Eco1")
		(23 "Eco2.User" user "User.Eco2")
		(25 "Edge.Cuts" user "Board Geometry/Outline")
		(27 "Margin" user)
		(31 "F.CrtYd" user "Package Geometry/Place Bound Top")
		(29 "B.CrtYd" user "Package Geometry/Place Bound Bottom")
		(35 "F.Fab" user "Ref Des/Assembly Top")
		(33 "B.Fab" user "Ref Des/Assembly Bottom")
	)
	(footprint ""
		(layer "F.Cu")
		(at 106.045 -87.503 -90)
		(property "Reference" "U40"
			(at 1.651 -3.21437 90)
			(unlocked yes)
			(layer "F.SilkS")
			(effects
				(font
					(size 0.7874 0.5842)
					(thickness 0.1524)
				)
			)
		)
		(property "Value" ""
			(at 0 0 270)
			(layer "F.Fab")
			(effects
				(font
					(size 1.27 1.27)
				)
			)
		)
		(property "Device Type" "NLASB3157DFT2G_SC88-G223-10187A"
			(at 0.1524 2.168906 270)
			(unlocked yes)
			(layer "F.Fab")
			(hide yes)
			(effects
				(font
					(size 0.7874 0.5842)
					(thickness 0.000001)
				)
			)
		)
		(property "User Part Number" "PARTNUM*"
			(at 0.127 3.184906 270)
			(unlocked yes)
			(layer "Cmts.User")
			(hide yes)
			(effects
				(font
					(size 0.7874 0.5842)
					(thickness 0.000001)
				)
			)
		)
		(duplicate_pad_numbers_are_jumpers no)
		(fp_line
			(start -1.50876 1.354074)
			(end -1.50876 -1.354074)
			(stroke
				(width 0.1)
				(type default)
			)
			(layer "F.SilkS")
		)
		(fp_line
			(start 1.50876 1.354074)
			(end -1.50876 1.354074)
			(stroke
				(width 0.1)
				(type default)
			)
			(layer "F.SilkS")
		)
		(fp_line
			(start -1.50876 -1.354074)
			(end 1.50876 -1.354074)
			(stroke
				(width 0.1)
				(type default)
			)
			(layer "F.SilkS")
		)
		(fp_line
			(start 1.50876 -1.354074)
			(end 1.50876 1.354074)
			(stroke
				(width 0.1)
				(type default)
			)
			(layer "F.SilkS")
		)
		(fp_poly
			(pts
				(arc
					(start -1.905 -2.159)
					(mid -1.905 -1.397)
					(end -1.905 -2.159)
				)
			)
			(stroke
				(width 0)
				(type default)
			)
			(fill yes)
			(layer "F.SilkS")
		)
		(fp_poly
			(pts
				(xy -1.76276 1.608074) (xy 1.76276 1.608074) (xy 1.76276 -1.608074) (xy -1.76276 -1.608074)
			)
			(stroke
				(width 0)
				(type default)
			)
			(fill no)
			(layer "F.CrtYd")
		)
		(fp_line
			(start -0.674878 1.100074)
			(end -0.674878 -1.100074)
			(stroke
				(width 0.1)
				(type default)
			)
			(layer "F.Fab")
		)
		(fp_line
			(start 0.674878 1.100074)
			(end -0.674878 1.100074)
			(stroke
				(width 0.1)
				(type default)
			)
			(layer "F.Fab")
		)
		(fp_line
			(start -0.674878 -1.100074)
			(end 0.674878 -1.100074)
			(stroke
				(width 0.1)
				(type default)
			)
			(layer "F.Fab")
		)
		(fp_line
			(start 0.674878 -1.100074)
			(end 0.674878 1.100074)
			(stroke
				(width 0.1)
				(type default)
			)
			(layer "F.Fab")
		)
		(fp_poly
			(pts
				(arc
					(start -2.159 -1.3716)
					(mid -2.159 -0.6096)
					(end -2.159 -1.3716)
				)
			)
			(stroke
				(width 0)
				(type default)
			)
			(fill yes)
			(layer "F.Fab")
		)
		(fp_text user "4"
			(at 2.06375 1.27 0)
			(unlocked yes)
			(layer "F.SilkS")
			(effects
				(font
					(size 0.635 0.4064)
					(thickness 0.1524)
				)
			)
		)
		(fp_text user "3"
			(at -2.00025 1.143 0)
			(unlocked yes)
			(layer "F.SilkS")
			(effects
				(font
					(size 0.635 0.4064)
					(thickness 0.1524)
				)
			)
		)
		(fp_text user "6"
			(at 2.06375 -1.27 0)
			(unlocked yes)
			(layer "F.SilkS")
			(effects
				(font
					(size 0.635 0.4064)
					(thickness 0.1524)
				)
			)
		)
		(fp_text user "4"
			(at 2.035048 0.924306 90)
			(unlocked yes)
			(layer "F.Fab")
			(effects
				(font
					(size 0.7874 0.5842)
					(thickness 0.1524)
				)
			)
		)
		(fp_text user "3"
			(at -1.995678 0.91313 90)
			(unlocked yes)
			(layer "F.Fab")
			(effects
				(font
					(size 0.7874 0.5842)
					(thickness 0.1524)
				)
			)
		)
		(fp_text user "6"
			(at 1.97104 -0.731774 90)
			(unlocked yes)
			(layer "F.Fab")
			(effects
				(font
					(size 0.7874 0.5842)
					(thickness 0.1524)
				)
			)
		)
		(pad "1" smd rect
			(at -0.94996 -0.649986 270)
			(size 0.6096 0.4318)
			(layers "F.Cu" "F.Mask" "F.Paste")
			(net "Net_786")
		)
		(pad "2" smd rect
			(at -0.94996 0 270)
			(size 0.6096 0.4318)
			(layers "F.Cu" "F.Mask" "F.Paste")
			(net "SG")
		)
		(pad "3" smd rect
			(at -0.94996 0.649986 270)
			(size 0.6096 0.4318)
			(layers "F.Cu" "F.Mask" "F.Paste")
			(net "FLASH_DQ3")
		)
		(pad "4" smd rect
			(at 0.94996 0.649986 270)
			(size 0.6096 0.4318)
			(layers "F.Cu" "F.Mask" "F.Paste")
			(net "FPGA_FLASH_DQ3")
		)
		(pad "5" smd rect
			(at 0.94996 0 270)
			(size 0.6096 0.4318)
			(layers "F.Cu" "F.Mask" "F.Paste")
			(net "XP3R3V_FPGA")
		)
		(pad "6" smd rect
			(at 0.94996 -0.649986 270)
			(size 0.6096 0.4318)
			(layers "F.Cu" "F.Mask" "F.Paste")
			(net "MUX2_SEL")
		)
	)
	(footprint ""
		(layer "F.Cu")
		(at 94.7166 -72.0598 90)
		(property "Reference" "C194"
			(at 19.8882 -27.49423 90)
			(unlocked yes)
			(layer "F.SilkS")
			(effects
				(font
					(size 0.7874 0.5842)
					(thickness 0.1524)
				)
			)
		)
		(property "Value" "VAL*"
			(at 0.0762 3.134106 90)
			(unlocked yes)
			(layer "F.Fab")
			(hide yes)
			(effects
				(font
					(size 0.7874 0.5842)
					(thickness 0.1524)
				)
			)
		)
		(property "Device Type" "CAPACITOR-G107-0F106-EM,10UF,2A"
			(at 0.0508 2.194306 90)
			(unlocked yes)
			(layer "F.Fab")
			(hide yes)
			(effects
				(font
					(size 0.7874 0.5842)
					(thickness 0.1524)
				)
			)
		)
		(property "User Part Number" "PARTNUM*"
			(at 0.1016 5.013706 90)
			(unlocked yes)
			(layer "Cmts.User")
			(hide yes)
			(effects
				(font
					(size 0.7874 0.5842)
					(thickness 0.1524)
				)
			)
		)
		(property "Tolerance" "TOL*"
			(at 0.0762 4.048506 90)
			(unlocked yes)
			(layer "Cmts.User")
			(hide yes)
			(effects
				(font
					(size 0.7874 0.5842)
					(thickness 0.1524)
				)
			)
		)
		(duplicate_pad_numbers_are_jumpers no)
		(fp_line
			(start 1.5748 -0.9398)
			(end -1.5748 -0.9398)
			(stroke
				(width 0.1)
				(type default)
			)
			(layer "F.SilkS")
		)
		(fp_line
			(start -1.5748 -0.9398)
			(end -1.5748 0.9398)
			(stroke
				(width 0.1)
				(type default)
			)
			(layer "F.SilkS")
		)
		(fp_line
			(start 1.5748 0.9398)
			(end 1.5748 -0.9398)
			(stroke
				(width 0.1)
				(type default)
			)
			(layer "F.SilkS")
		)
		(fp_line
			(start -1.5748 0.9398)
			(end 1.5748 0.9398)
			(stroke
				(width 0.1)
				(type default)
			)
			(layer "F.SilkS")
		)
		(fp_rect
			(start 1.5748 -0.9398)
			(end -1.5748 0.9398)
			(stroke
				(width 0)
				(type default)
			)
			(fill no)
			(layer "F.CrtYd")
		)
		(fp_line
			(start 1.016 -0.635)
			(end -1.016 -0.635)
			(stroke
				(width 0.1)
				(type default)
			)
			(layer "F.Fab")
		)
		(fp_line
			(start -1.016 -0.635)
			(end -1.016 0.635)
			(stroke
				(width 0.1)
				(type default)
			)
			(layer "F.Fab")
		)
		(fp_line
			(start 1.016 0.635)
			(end 1.016 -0.635)
			(stroke
				(width 0.1)
				(type default)
			)
			(layer "F.Fab")
		)
		(fp_line
			(start -1.016 0.635)
			(end 1.016 0.635)
			(stroke
				(width 0.1)
				(type default)
			)
			(layer "F.Fab")
		)
		(pad "1" smd rect
			(at -0.8382 0 90)
			(size 0.9652 1.3716)
			(layers "F.Cu" "F.Mask" "F.Paste")
			(net "XP1R2V_FPGA")
		)
		(pad "2" smd rect
			(at 0.8382 0 90)
			(size 0.9652 1.3716)
			(layers "F.Cu" "F.Mask" "F.Paste")
			(net "SG")
		)
		(zone
			(layer "F.Cu")
			(hatch none 0.5)
			(connect_pads
				(clearance 0)
			)
			(min_thickness 0.25)
			(keepout
				(tracks allowed)
				(vias not_allowed)
				(pads allowed)
				(copperpour not_allowed)
				(footprints allowed)
			)
			(placement
				(enabled no)
				(sheetname "")
			)
			(fill
				(thermal_gap 0.5)
				(thermal_bridge_width 0.5)
				(island_removal_mode 0)
			)
			(polygon
				(pts
					(xy 94.0816 -72.2884) (xy 94.0816 -71.8312) (xy 95.3516 -71.8312) (xy 95.3516 -72.2884)
				)
			)
		)
	)
)
